# S9S_MB_2U (Grand Teton) — schematic netlist excerpt (pin names and nets, part order shuffled) for the footprints in the layout excerpt that follows; sources: Cadence DE-HDL packaged netlist, KiCad conversion of 03242023_DA0F0TMBIJ0_F0T_Motherboard_J_brd_V01_OCP.brd

C1539  Q_CAP_DIFFBUS  DIFF BUS_0.22UF 6.3V 20% X6S  pkg C0201  page 177 : \1\ = P5E_CPU1_PE3_TX_C_DP<4> ; \2\ = P5E_CPU1_PE3_TX_DP<4>
R3485  Q_RES  33.2 1% CHIP  pkg 0402LF  page 213 : A = GPU_WP_HW_CTRL_N ; B = GPU_WP_HW_CTRL_R_N

(kicad_pcb
	(version 20260206)
	(generator "pcbnew")
	(generator_version "10.0")
	(general
		(thickness 1.6)
		(legacy_teardrops no)
	)
	(paper "A4")
	(title_block
		(title "03242023_DA0F0TMBIJ0_F0T_Motherboard_J_brd_V01_OCP.brd")
		(comment 1 "Grand Teton / footprints 356-357 of 6105")
	)
	(layers
		(0 "F.Cu" signal "TOP")
		(4 "In1.Cu" signal "GND")
		(6 "In2.Cu" signal "IN1")
		(8 "In3.Cu" signal "GND1")
		(10 "In4.Cu" signal "IN2")
		(12 "In5.Cu" signal "GND2")
		(14 "In6.Cu" signal "IN3")
		(16 "In7.Cu" signal "GND3")
		(18 "In8.Cu" signal "VCC")
		(20 "In9.Cu" signal "VCC1")
		(22 "In10.Cu" signal "GND4")
		(24 "In11.Cu" signal "IN4")
		(26 "In12.Cu" signal "GND5")
		(28 "In13.Cu" signal "IN5")
		(30 "In14.Cu" signal "GND6")
		(32 "In15.Cu" signal "IN6")
		(34 "In16.Cu" signal "GND7")
		(2 "B.Cu" signal "BOTTOM")
		(9 "F.Adhes" user "F.Adhesive")
		(11 "B.Adhes" user "B.Adhesive")
		(13 "F.Paste" user "Package Geometry/Pastemask Top")
		(15 "B.Paste" user "Package Geometry/Pastemask Bottom")
		(5 "F.SilkS" user "Ref Des/Silkscreen Top")
		(7 "B.SilkS" user "Ref Des/Silkscreen Bottom")
		(1 "F.Mask" user "Board Geometry/Soldermask Top")
		(3 "B.Mask" user "Board Geometry/Soldermask Bottom")
		(17 "Dwgs.User" user "User.Drawings")
		(19 "Cmts.User" user "User.Comments")
		(21 "Eco1.User" user "User.Eco1")
		(23 "Eco2.User" user "User.Eco2")
		(25 "Edge.Cuts" user "Board Geometry/Outline")
		(27 "Margin" user)
		(31 "F.CrtYd" user "Package Geometry/Place Bound Top")
		(29 "B.CrtYd" user "Package Geometry/Place Bound Bottom")
		(35 "F.Fab" user "Ref Des/Assembly Top")
		(33 "B.Fab" user "Ref Des/Assembly Bottom")
	)
	(footprint ""
		(layer "F.Cu")
		(at 164.64788 -113.756948)
		(property "Reference" "R3485"
			(at 0 0 0)
			(layer "F.SilkS")
			(hide yes)
			(effects
				(font
					(size 1.27 1.27)
				)
			)
		)
		(property "Value" ""
			(at 0 0 0)
			(layer "F.Fab")
			(effects
				(font
					(size 1.27 1.27)
				)
			)
		)
		(duplicate_pad_numbers_are_jumpers no)
		(fp_line
			(start -0.7874 -0.4064)
			(end 0.7874 -0.4064)
			(stroke
				(width 0.1524)
				(type default)
			)
			(layer "F.SilkS")
		)
		(fp_line
			(start -0.7874 0.4064)
			(end -0.7874 -0.4064)
			(stroke
				(width 0.1524)
				(type default)
			)
			(layer "F.SilkS")
		)
		(fp_line
			(start 0.7874 -0.4064)
			(end 0.7874 0.4064)
			(stroke
				(width 0.1524)
				(type default)
			)
			(layer "F.SilkS")
		)
		(fp_line
			(start 0.7874 0.4064)
			(end -0.7874 0.4064)
			(stroke
				(width 0.1524)
				(type default)
			)
			(layer "F.SilkS")
		)
		(fp_line
			(start -0.67945 -0.305054)
			(end -0.12065 -0.305054)
			(stroke
				(width 0.1)
				(type default)
			)
			(layer "F.Fab")
		)
		(fp_line
			(start -0.67945 0.3048)
			(end -0.67945 -0.305054)
			(stroke
				(width 0.1)
				(type default)
			)
			(layer "F.Fab")
		)
		(fp_line
			(start -0.12065 -0.305054)
			(end -0.12065 -0.2794)
			(stroke
				(width 0.1)
				(type default)
			)
			(layer "F.Fab")
		)
		(fp_line
			(start -0.12065 -0.2794)
			(end 0.12065 -0.2794)
			(stroke
				(width 0.1)
				(type default)
			)
			(layer "F.Fab")
		)
		(fp_line
			(start -0.12065 0.2794)
			(end -0.12065 0.3048)
			(stroke
				(width 0.1)
				(type default)
			)
			(layer "F.Fab")
		)
		(fp_line
			(start -0.12065 0.3048)
			(end -0.67945 0.3048)
			(stroke
				(width 0.1)
				(type default)
			)
			(layer "F.Fab")
		)
		(fp_line
			(start 0.120396 0.2794)
			(end -0.12065 0.2794)
			(stroke
				(width 0.1)
				(type default)
			)
			(layer "F.Fab")
		)
		(fp_line
			(start 0.120396 0.3048)
			(end 0.120396 0.2794)
			(stroke
				(width 0.1)
				(type default)
			)
			(layer "F.Fab")
		)
		(fp_line
			(start 0.12065 -0.3048)
			(end 0.67945 -0.3048)
			(stroke
				(width 0.1)
				(type default)
			)
			(layer "F.Fab")
		)
		(fp_line
			(start 0.12065 -0.2794)
			(end 0.12065 -0.3048)
			(stroke
				(width 0.1)
				(type default)
			)
			(layer "F.Fab")
		)
		(fp_line
			(start 0.67945 -0.3048)
			(end 0.67945 0.3048)
			(stroke
				(width 0.1)
				(type default)
			)
			(layer "F.Fab")
		)
		(fp_line
			(start 0.67945 0.3048)
			(end 0.120396 0.3048)
			(stroke
				(width 0.1)
				(type default)
			)
			(layer "F.Fab")
		)
		(pad "1" smd circle
			(at -0.40005 0)
			(size 0 0)
			(layers "F.Cu" "F.Mask" "F.Paste")
			(net "GPU_WP_HW_CTRL_N")
		)
		(pad "2" smd circle
			(at 0.40005 0)
			(size 0 0)
			(layers "F.Cu" "F.Mask" "F.Paste")
			(net "GPU_WP_HW_CTRL_R_N")
		)
	)
	(footprint ""
		(layer "F.Cu")
		(at 156.085794 -408.517344 -90)
		(property "Reference" "C1539"
			(at 0 0 270)
			(layer "F.SilkS")
			(hide yes)
			(effects
				(font
					(size 1.27 1.27)
				)
			)
		)
		(property "Value" ""
			(at 0 0 270)
			(layer "F.Fab")
			(effects
				(font
					(size 1.27 1.27)
				)
			)
		)
		(duplicate_pad_numbers_are_jumpers no)
		(fp_line
			(start -0.299974 0.150114)
			(end -0.299974 -0.150114)
			(stroke
				(width 0.1)
				(type default)
			)
			(layer "F.Fab")
		)
		(fp_line
			(start 0.299974 0.150114)
			(end -0.299974 0.150114)
			(stroke
				(width 0.1)
				(type default)
			)
			(layer "F.Fab")
		)
		(fp_line
			(start -0.299974 -0.150114)
			(end 0.299974 -0.150114)
			(stroke
				(width 0.1)
				(type default)
			)
			(layer "F.Fab")
		)
		(fp_line
			(start 0.299974 -0.150114)
			(end 0.299974 0.150114)
			(stroke
				(width 0.1)
				(type default)
			)
			(layer "F.Fab")
		)
		(pad "1" smd rect
			(at -0.2667 0 270)
			(size 0.3048 0.381)
			(layers "F.Cu" "F.Mask" "F.Paste")
			(net "P5E_CPU1_PE3_TX_C_DP<4>")
		)
		(pad "2" smd rect
			(at 0.2667 0 270)
			(size 0.3048 0.381)
			(layers "F.Cu" "F.Mask" "F.Paste")
			(net "P5E_CPU1_PE3_TX_DP<4>")
		)
	)
)
